(kicad_pcb
	(version 20260206)
	(generator "pcbnew")
	(generator_version "10.0")
	(general
		(thickness 1.6)
		(legacy_teardrops no)
	)
	(paper "A4")
	(title_block
		(title "Bryce Canyon_F.DPB_16315-1-OCP.brd")
		(comment 1 "Bryce Canyon / footprints 247-253 of 2223")
	)
	(layers
		(0 "F.Cu" signal "TOP")
		(4 "In1.Cu" signal "L2GND")
		(6 "In2.Cu" signal "L3")
		(8 "In3.Cu" signal "L4GND")
		(10 "In4.Cu" signal "L5")
		(12 "In5.Cu" signal "L6VCC")
		(14 "In6.Cu" signal "L7VCC")
		(16 "In7.Cu" signal "L8")
		(18 "In8.Cu" signal "L9GND")
		(20 "In9.Cu" signal "L10")
		(22 "In10.Cu" signal "L11GND")
		(2 "B.Cu" signal "BOTTOM")
		(9 "F.Adhes" user "F.Adhesive")
		(11 "B.Adhes" user "B.Adhesive")
		(13 "F.Paste" user "Package Geometry/Pastemask Top")
		(15 "B.Paste" user "Package Geometry/Pastemask Bottom")
		(5 "F.SilkS" user "Ref Des/Silkscreen Top")
		(7 "B.SilkS" user "Ref Des/Silkscreen Bottom")
		(1 "F.Mask" user "Board Geometry/Soldermask Top")
		(3 "B.Mask" user "Board Geometry/Soldermask Bottom")
		(17 "Dwgs.User" user "User.Drawings")
		(19 "Cmts.User" user "User.Comments")
		(21 "Eco1.User" user "User.Eco1")
		(23 "Eco2.User" user "User.Eco2")
		(25 "Edge.Cuts" user "Board Geometry/Outline")
		(27 "Margin" user)
		(31 "F.CrtYd" user "Package Geometry/Place Bound Top")
		(29 "B.CrtYd" user "Package Geometry/Place Bound Bottom")
		(35 "F.Fab" user "Ref Des/Assembly Top")
		(33 "B.Fab" user "Ref Des/Assembly Bottom")
	)
	(footprint ""
		(layer "F.Cu")
		(at 178.181 -48.554894 180)
		(property "Reference" "Q175"
			(at 0 0 180)
			(layer "F.SilkS")
			(hide yes)
			(effects
				(font
					(size 1.27 1.27)
				)
			)
		)
		(property "Value" "2N7002KDW-GP"
			(at -2.3622 -8.2042 180)
			(unlocked yes)
			(layer "F.Fab")
			(hide yes)
			(effects
				(font
					(size 1.016 1.016)
					(thickness 0.1524)
				)
			)
		)
		(property "Device Type" "SOT-363H44"
			(at -2.3622 -10.1092 180)
			(unlocked yes)
			(layer "F.Fab")
			(hide yes)
			(effects
				(font
					(size 1.016 1.016)
					(thickness 0.1524)
				)
			)
		)
		(duplicate_pad_numbers_are_jumpers no)
		(fp_line
			(start 1.4478 1.7018)
			(end 1.4478 -1.7018)
			(stroke
				(width 0.1524)
				(type default)
			)
			(layer "F.SilkS")
		)
		(fp_line
			(start 1.4478 -1.7018)
			(end -1.4478 -1.7018)
			(stroke
				(width 0.1524)
				(type default)
			)
			(layer "F.SilkS")
		)
		(fp_line
			(start -1.27 1.524)
			(end -1.27 0.6604)
			(stroke
				(width 0.4826)
				(type default)
			)
			(layer "F.SilkS")
		)
		(fp_line
			(start -1.4478 1.7018)
			(end 1.4478 1.7018)
			(stroke
				(width 0.1524)
				(type default)
			)
			(layer "F.SilkS")
		)
		(fp_line
			(start -1.4478 -1.7018)
			(end -1.4478 1.7018)
			(stroke
				(width 0.1524)
				(type default)
			)
			(layer "F.SilkS")
		)
		(fp_poly
			(pts
				(xy -1.524 -1.778) (xy 1.524 -1.778) (xy 1.524 1.778) (xy -1.524 1.778)
			)
			(stroke
				(width 0)
				(type default)
			)
			(fill no)
			(layer "F.CrtYd")
		)
		(fp_poly
			(pts
				(xy -1.524 -1.778) (xy 1.524 -1.778) (xy 1.524 1.778) (xy -1.524 1.778)
			)
			(stroke
				(width 0)
				(type default)
			)
			(fill no)
			(layer "F.Fab")
		)
		(pad "1" smd rect
			(at -0.65024 0.9398 180)
			(size 0.4064 1.016)
			(layers "F.Cu" "F.Mask" "F.Paste")
			(net "GND")
		)
		(pad "2" smd rect
			(at 0 0.9398 180)
			(size 0.4064 1.016)
			(layers "F.Cu" "F.Mask" "F.Paste")
			(net "SW_PWR_R_HDD29")
		)
		(pad "3" smd rect
			(at 0.65024 0.9398 180)
			(size 0.4064 1.016)
			(layers "F.Cu" "F.Mask" "F.Paste")
			(net "SW_HDD_P29")
		)
		(pad "4" smd rect
			(at 0.65024 -0.9398 180)
			(size 0.4064 1.016)
			(layers "F.Cu" "F.Mask" "F.Paste")
			(net "GND")
		)
		(pad "5" smd rect
			(at 0 -0.9398 180)
			(size 0.4064 1.016)
			(layers "F.Cu" "F.Mask" "F.Paste")
			(net "SW_HDD_G29")
		)
		(pad "6" smd rect
			(at -0.65024 -0.9398 180)
			(size 0.4064 1.016)
			(layers "F.Cu" "F.Mask" "F.Paste")
			(net "SW_HDD_R29")
		)
	)
	(footprint ""
		(layer "F.Cu")
		(at 87.036148 -71.287894)
		(property "Reference" "C383"
			(at 0 0 0)
			(layer "F.SilkS")
			(hide yes)
			(effects
				(font
					(size 1.27 1.27)
				)
			)
		)
		(property "Value" "SC4D7U25V5KX-1-GP"
			(at -0.0762 -6.1214 0)
			(unlocked yes)
			(layer "F.Fab")
			(hide yes)
			(effects
				(font
					(size 1.016 1.016)
					(thickness 0.1524)
				)
			)
		)
		(property "Device Type" "C805H58"
			(at -0.0762 -8.1534 0)
			(unlocked yes)
			(layer "F.Fab")
			(hide yes)
			(effects
				(font
					(size 1.016 1.016)
					(thickness 0.1524)
				)
			)
		)
		(duplicate_pad_numbers_are_jumpers no)
		(fp_line
			(start 0.635 0)
			(end -0.635 0)
			(stroke
				(width 0.508)
				(type default)
			)
			(layer "F.SilkS")
		)
		(fp_rect
			(start -0.9652 1.778)
			(end 0.9652 -1.778)
			(stroke
				(width 0)
				(type default)
			)
			(fill no)
			(layer "F.CrtYd")
		)
		(fp_poly
			(pts
				(xy -0.9652 -1.778) (xy 0.9652 -1.778) (xy 0.9652 1.778) (xy -0.9652 1.778)
			)
			(stroke
				(width 0)
				(type default)
			)
			(fill no)
			(layer "F.Fab")
		)
		(pad "1" smd rect
			(at 0 -0.9652)
			(size 1.397 1.143)
			(layers "F.Cu" "F.Mask" "F.Paste")
			(net "P12V_HDD26")
		)
		(pad "2" smd rect
			(at 0 0.9652)
			(size 1.397 1.143)
			(layers "F.Cu" "F.Mask" "F.Paste")
			(net "GND")
		)
	)
	(footprint ""
		(layer "F.Cu")
		(at 361.369102 -304.335942 180)
		(property "Reference" "C138"
			(at 0 0 180)
			(layer "F.SilkS")
			(hide yes)
			(effects
				(font
					(size 1.27 1.27)
				)
			)
		)
		(property "Value" "SC1U25V3KX-GP"
			(at 0 -2.8194 180)
			(unlocked yes)
			(layer "F.Fab")
			(hide yes)
			(effects
				(font
					(size 1.016 1.016)
					(thickness 0.1524)
				)
			)
		)
		(property "Device Type" "C603H36"
			(at 0 -4.3434 180)
			(unlocked yes)
			(layer "F.Fab")
			(hide yes)
			(effects
				(font
					(size 1.016 1.016)
					(thickness 0.1524)
				)
			)
		)
		(duplicate_pad_numbers_are_jumpers no)
		(fp_line
			(start 0.508 0)
			(end -0.508 0)
			(stroke
				(width 0.2032)
				(type default)
			)
			(layer "F.SilkS")
		)
		(fp_rect
			(start -0.5842 1.3335)
			(end 0.5842 -1.3335)
			(stroke
				(width 0)
				(type default)
			)
			(fill no)
			(layer "F.CrtYd")
		)
		(fp_rect
			(start -0.5842 1.3335)
			(end 0.5842 -1.3335)
			(stroke
				(width 0)
				(type default)
			)
			(fill no)
			(layer "F.Fab")
		)
		(pad "1" smd custom
			(at 0 -0.762 180)
			(size 0.2159 0.2159)
			(layers "F.Cu" "F.Mask" "F.Paste")
			(net "P12V_HDD7")
			(options
				(clearance outline)
				(anchor circle)
			)
			(primitives
				(gr_poly
					(pts
						(arc
							(start -0.3302 -0.4318)
							(mid -0.402042 -0.402042)
							(end -0.4318 -0.3302)
						)
						(arc
							(start -0.4318 0.3302)
							(mid -0.402042 0.402042)
							(end -0.3302 0.4318)
						)
						(arc
							(start 0.3302 0.4318)
							(mid 0.402042 0.402042)
							(end 0.4318 0.3302)
						)
						(arc
							(start 0.4318 -0.3302)
							(mid 0.402042 -0.402042)
							(end 0.3302 -0.4318)
						)
					)
					(width 0)
					(fill yes)
				)
			)
		)
		(pad "2" smd custom
			(at 0 0.762 180)
			(size 0.2159 0.2159)
			(layers "F.Cu" "F.Mask" "F.Paste")
			(net "GND")
			(options
				(clearance outline)
				(anchor circle)
			)
			(primitives
				(gr_poly
					(pts
						(arc
							(start -0.3302 -0.4318)
							(mid -0.402042 -0.402042)
							(end -0.4318 -0.3302)
						)
						(arc
							(start -0.4318 0.3302)
							(mid -0.402042 0.402042)
							(end -0.3302 0.4318)
						)
						(arc
							(start 0.3302 0.4318)
							(mid 0.402042 0.402042)
							(end 0.4318 0.3302)
						)
						(arc
							(start 0.4318 -0.3302)
							(mid 0.402042 -0.402042)
							(end 0.3302 -0.4318)
						)
					)
					(width 0)
					(fill yes)
				)
			)
		)
	)
	(footprint ""
		(layer "F.Cu")
		(at 346.700094 -209.399886)
		(property "Reference" "FLED8"
			(at 0 0 0)
			(layer "F.SilkS")
			(hide yes)
			(effects
				(font
					(size 1.27 1.27)
				)
			)
		)
		(property "Value" "LED-BY-19-GP"
			(at -2.132076 1.414018 0)
			(unlocked yes)
			(layer "F.Fab")
			(hide yes)
			(effects
				(font
					(size 1.016 1.016)
					(thickness 0.1524)
				)
			)
		)
		(property "Device Type" "LED-1615-4PH26"
			(at -2.132076 -0.109982 0)
			(unlocked yes)
			(layer "F.Fab")
			(hide yes)
			(effects
				(font
					(size 1.016 1.016)
					(thickness 0.1524)
				)
			)
		)
		(duplicate_pad_numbers_are_jumpers no)
		(fp_line
			(start -1.2954 0.254)
			(end -1.2954 1.6002)
			(stroke
				(width 0.508)
				(type default)
			)
			(layer "F.SilkS")
		)
		(fp_line
			(start -1.2954 1.6002)
			(end 1.2954 1.6002)
			(stroke
				(width 0.508)
				(type default)
			)
			(layer "F.SilkS")
		)
		(fp_line
			(start -1.1176 -1.4224)
			(end 1.1176 -1.4224)
			(stroke
				(width 0.1524)
				(type default)
			)
			(layer "F.SilkS")
		)
		(fp_line
			(start -1.1176 1.4224)
			(end -1.1176 -1.4224)
			(stroke
				(width 0.1524)
				(type default)
			)
			(layer "F.SilkS")
		)
		(fp_line
			(start 1.1176 -1.4224)
			(end 1.1176 1.4224)
			(stroke
				(width 0.1524)
				(type default)
			)
			(layer "F.SilkS")
		)
		(fp_line
			(start 1.1176 1.4224)
			(end -1.1176 1.4224)
			(stroke
				(width 0.1524)
				(type default)
			)
			(layer "F.SilkS")
		)
		(fp_line
			(start 1.2954 1.6002)
			(end 1.2954 0.254)
			(stroke
				(width 0.508)
				(type default)
			)
			(layer "F.SilkS")
		)
		(fp_rect
			(start -0.7493 0.8001)
			(end 0.7493 -0.8001)
			(stroke
				(width 0)
				(type default)
			)
			(fill no)
			(layer "F.CrtYd")
		)
		(fp_poly
			(pts
				(xy -1.3716 1.6764) (xy -1.3716 -1.6764) (xy 1.3716 -1.6764) (xy 1.3716 0.0635) (xy 0.7493 0.0635)
				(xy 0.7493 -0.8001) (xy -0.7493 -0.8001) (xy -0.7493 0.8001) (xy 0.7493 0.8001) (xy 0.7493 0.0762)
				(xy 1.3716 0.0762) (xy 1.3716 1.6764)
			)
			(stroke
				(width 0)
				(type default)
			)
			(fill no)
			(layer "F.CrtYd")
		)
		(fp_rect
			(start -1.3716 1.6764)
			(end 1.3716 -1.6764)
			(stroke
				(width 0)
				(type default)
			)
			(fill no)
			(layer "F.Fab")
		)
		(pad "1" smd rect
			(at 0.50038 -0.73025)
			(size 0.7112 0.8636)
			(layers "F.Cu" "F.Mask" "F.Paste")
			(net "DRV_ACT_7")
		)
		(pad "2" smd rect
			(at -0.50038 -0.73025)
			(size 0.7112 0.8636)
			(layers "F.Cu" "F.Mask" "F.Paste")
			(net "FLT_HDD7")
		)
		(pad "3" smd rect
			(at 0.50038 0.73025)
			(size 0.7112 0.8636)
			(layers "F.Cu" "F.Mask" "F.Paste")
			(net "DRV_ACT_7_N")
		)
		(pad "4" smd rect
			(at -0.50038 0.73025)
			(size 0.7112 0.8636)
			(layers "F.Cu" "F.Mask" "F.Paste")
			(net "FLT_HDD7_N")
		)
	)
	(footprint ""
		(layer "F.Cu")
		(at 381.38735 -62.143894 90)
		(property "Reference" "R866"
			(at 0 0 90)
			(layer "F.SilkS")
			(hide yes)
			(effects
				(font
					(size 1.27 1.27)
				)
			)
		)
		(property "Value" "10KR2F-2-GP"
			(at 0.064008 -3.993896 90)
			(unlocked yes)
			(layer "F.Fab")
			(hide yes)
			(effects
				(font
					(size 1.016 1.016)
					(thickness 0.1524)
				)
			)
		)
		(property "Device Type" "R402H16"
			(at 0.064008 -5.517896 90)
			(unlocked yes)
			(layer "F.Fab")
			(hide yes)
			(effects
				(font
					(size 1.016 1.016)
					(thickness 0.1524)
				)
			)
		)
		(duplicate_pad_numbers_are_jumpers no)
		(fp_line
			(start 0.508 -0.9398)
			(end -0.508 -0.9398)
			(stroke
				(width 0.1524)
				(type default)
			)
			(layer "F.SilkS")
		)
		(fp_line
			(start -0.508 -0.9398)
			(end -0.508 0.9398)
			(stroke
				(width 0.1524)
				(type default)
			)
			(layer "F.SilkS")
		)
		(fp_rect
			(start -0.508 0.9398)
			(end 0.508 -0.9398)
			(stroke
				(width 0)
				(type default)
			)
			(fill no)
			(layer "F.CrtYd")
		)
		(fp_rect
			(start -0.508 0.9398)
			(end 0.508 -0.9398)
			(stroke
				(width 0)
				(type default)
			)
			(fill no)
			(layer "F.Fab")
		)
		(pad "1" smd custom
			(at 0 -0.4445 90)
			(size 0.1397 0.1397)
			(layers "F.Cu" "F.Mask" "F.Paste")
			(net "P3V3_STBY_A")
			(options
				(clearance outline)
				(anchor circle)
			)
			(primitives
				(gr_poly
					(pts
						(arc
							(start -0.1778 -0.2794)
							(mid -0.249642 -0.249642)
							(end -0.2794 -0.1778)
						)
						(arc
							(start -0.2794 0.1778)
							(mid -0.249642 0.249642)
							(end -0.1778 0.2794)
						)
						(arc
							(start 0.1778 0.2794)
							(mid 0.249642 0.249642)
							(end 0.2794 0.1778)
						)
						(arc
							(start 0.2794 -0.1778)
							(mid 0.249642 -0.249642)
							(end 0.1778 -0.2794)
						)
					)
					(width 0)
					(fill yes)
				)
			)
		)
		(pad "2" smd custom
			(at 0 0.4445 90)
			(size 0.1397 0.1397)
			(layers "F.Cu" "F.Mask" "F.Paste")
			(net "HDD_PRSNT_32")
			(options
				(clearance outline)
				(anchor circle)
			)
			(primitives
				(gr_poly
					(pts
						(arc
							(start -0.1778 -0.2794)
							(mid -0.249642 -0.249642)
							(end -0.2794 -0.1778)
						)
						(arc
							(start -0.2794 0.1778)
							(mid -0.249642 0.249642)
							(end -0.1778 0.2794)
						)
						(arc
							(start 0.1778 0.2794)
							(mid 0.249642 0.249642)
							(end 0.2794 0.1778)
						)
						(arc
							(start 0.2794 -0.1778)
							(mid 0.249642 -0.249642)
							(end 0.1778 -0.2794)
						)
					)
					(width 0)
					(fill yes)
				)
			)
		)
	)
	(footprint ""
		(layer "F.Cu")
		(at 394.56995 -165.104318 90)
		(property "Reference" "C308"
			(at 0 0 90)
			(layer "F.SilkS")
			(hide yes)
			(effects
				(font
					(size 1.27 1.27)
				)
			)
		)
		(property "Value" "SCD033U25V2KX-GP"
			(at 1.1811 -2.7051 90)
			(unlocked yes)
			(layer "F.Fab")
			(hide yes)
			(effects
				(font
					(size 1.016 1.016)
					(thickness 0.1524)
				)
			)
		)
		(property "Device Type" "C402H22"
			(at 1.1811 -4.2291 90)
			(unlocked yes)
			(layer "F.Fab")
			(hide yes)
			(effects
				(font
					(size 1.016 1.016)
					(thickness 0.1524)
				)
			)
		)
		(duplicate_pad_numbers_are_jumpers no)
		(fp_rect
			(start -0.4318 0.9525)
			(end 0.4318 -0.9525)
			(stroke
				(width 0)
				(type default)
			)
			(fill no)
			(layer "F.CrtYd")
		)
		(fp_rect
			(start -0.4318 0.9525)
			(end 0.4318 -0.9525)
			(stroke
				(width 0)
				(type default)
			)
			(fill no)
			(layer "F.Fab")
		)
		(pad "1" smd custom
			(at 0 -0.4445 90)
			(size 0.1524 0.1524)
			(layers "F.Cu" "F.Mask" "F.Paste")
			(net "SW_HDD_P20")
			(options
				(clearance outline)
				(anchor circle)
			)
			(primitives
				(gr_poly
					(pts
						(arc
							(start 0.3048 -0.2032)
							(mid 0.275042 -0.275042)
							(end 0.2032 -0.3048)
						)
						(arc
							(start -0.2032 -0.3048)
							(mid -0.275042 -0.275042)
							(end -0.3048 -0.2032)
						)
						(arc
							(start -0.3048 0.2032)
							(mid -0.275042 0.275042)
							(end -0.2032 0.3048)
						)
						(arc
							(start 0.2032 0.3048)
							(mid 0.275042 0.275042)
							(end 0.3048 0.2032)
						)
					)
					(width 0)
					(fill yes)
				)
			)
		)
		(pad "2" smd custom
			(at 0 0.4445 90)
			(size 0.1524 0.1524)
			(layers "F.Cu" "F.Mask" "F.Paste")
			(net "GND")
			(options
				(clearance outline)
				(anchor circle)
			)
			(primitives
				(gr_poly
					(pts
						(arc
							(start 0.3048 -0.2032)
							(mid 0.275042 -0.275042)
							(end 0.2032 -0.3048)
						)
						(arc
							(start -0.2032 -0.3048)
							(mid -0.275042 -0.275042)
							(end -0.3048 -0.2032)
						)
						(arc
							(start -0.3048 0.2032)
							(mid -0.275042 0.275042)
							(end -0.2032 0.3048)
						)
						(arc
							(start 0.2032 0.3048)
							(mid 0.275042 0.275042)
							(end 0.3048 0.2032)
						)
					)
					(width 0)
					(fill yes)
				)
			)
		)
	)
	(footprint ""
		(layer "F.Cu")
		(at 261.932166 -339.754464 90)
		(property "Reference" "R381"
			(at 0 0 90)
			(layer "F.SilkS")
			(hide yes)
			(effects
				(font
					(size 1.27 1.27)
				)
			)
		)
		(property "Value" "10KR2F-2-GP"
			(at 0.064008 -3.993896 90)
			(unlocked yes)
			(layer "F.Fab")
			(hide yes)
			(effects
				(font
					(size 1.016 1.016)
					(thickness 0.1524)
				)
			)
		)
		(property "Device Type" "R402H16"
			(at 0.064008 -5.517896 90)
			(unlocked yes)
			(layer "F.Fab")
			(hide yes)
			(effects
				(font
					(size 1.016 1.016)
					(thickness 0.1524)
				)
			)
		)
		(duplicate_pad_numbers_are_jumpers no)
		(fp_line
			(start 0.508 -0.9398)
			(end -0.508 -0.9398)
			(stroke
				(width 0.1524)
				(type default)
			)
			(layer "F.SilkS")
		)
		(fp_line
			(start -0.508 -0.9398)
			(end -0.508 0.9398)
			(stroke
				(width 0.1524)
				(type default)
			)
			(layer "F.SilkS")
		)
		(fp_rect
			(start -0.508 0.9398)
			(end 0.508 -0.9398)
			(stroke
				(width 0)
				(type default)
			)
			(fill no)
			(layer "F.CrtYd")
		)
		(fp_rect
			(start -0.508 0.9398)
			(end 0.508 -0.9398)
			(stroke
				(width 0)
				(type default)
			)
			(fill no)
			(layer "F.Fab")
		)
		(pad "1" smd custom
			(at 0 -0.4445 90)
			(size 0.1397 0.1397)
			(layers "F.Cu" "F.Mask" "F.Paste")
			(net "P3V3_STBY_A")
			(options
				(clearance outline)
				(anchor circle)
			)
			(primitives
				(gr_poly
					(pts
						(arc
							(start -0.1778 -0.2794)
							(mid -0.249642 -0.249642)
							(end -0.2794 -0.1778)
						)
						(arc
							(start -0.2794 0.1778)
							(mid -0.249642 0.249642)
							(end -0.1778 0.2794)
						)
						(arc
							(start 0.1778 0.2794)
							(mid 0.249642 0.249642)
							(end 0.2794 0.1778)
						)
						(arc
							(start 0.2794 -0.1778)
							(mid 0.249642 -0.249642)
							(end 0.1778 -0.2794)
						)
					)
					(width 0)
					(fill yes)
				)
			)
		)
		(pad "2" smd custom
			(at 0 0.4445 90)
			(size 0.1397 0.1397)
			(layers "F.Cu" "F.Mask" "F.Paste")
			(net "SCC_A_TYPE_0")
			(options
				(clearance outline)
				(anchor circle)
			)
			(primitives
				(gr_poly
					(pts
						(arc
							(start -0.1778 -0.2794)
							(mid -0.249642 -0.249642)
							(end -0.2794 -0.1778)
						)
						(arc
							(start -0.2794 0.1778)
							(mid -0.249642 0.249642)
							(end -0.1778 0.2794)
						)
						(arc
							(start 0.1778 0.2794)
							(mid 0.249642 0.249642)
							(end 0.2794 0.1778)
						)
						(arc
							(start 0.2794 -0.1778)
							(mid 0.249642 -0.249642)
							(end 0.1778 -0.2794)
						)
					)
					(width 0)
					(fill yes)
				)
			)
		)
	)
)
